# T6G (Grand Teton) — schematic netlist excerpt (pin names and nets, part order shuffled) for the footprints in the layout excerpt that follows; sources: Cadence DE-HDL packaged netlist, KiCad conversion of 04192023_DAF0TMB3IC0_F0TG_MB_C_brd_V02_OCP.brd

R4132  Q_RES  100K 1% EMPTY  pkg 0402LF  page 125 : A = GPU_3V3IO_RSVD3_FFU ; B = GND
R3291  Q_RES  4.7K 1% EMPTY  pkg 0402LF  page 111 : A = PU_TEST ; B = GND

(kicad_pcb
	(version 20260206)
	(generator "pcbnew")
	(generator_version "10.0")
	(general
		(thickness 1.6)
		(legacy_teardrops no)
	)
	(paper "A4")
	(title_block
		(title "04192023_DAF0TMB3IC0_F0TG_MB_C_brd_V02_OCP.brd")
		(comment 1 "Grand Teton / footprints 3278-3279 of 8354")
	)
	(layers
		(0 "F.Cu" signal "TOP")
		(4 "In1.Cu" signal "GND")
		(6 "In2.Cu" signal "IN1")
		(8 "In3.Cu" signal "GND1")
		(10 "In4.Cu" signal "IN2")
		(12 "In5.Cu" signal "GND2")
		(14 "In6.Cu" signal "IN3")
		(16 "In7.Cu" signal "GND3")
		(18 "In8.Cu" signal "VCC")
		(20 "In9.Cu" signal "VCC1")
		(22 "In10.Cu" signal "GND4")
		(24 "In11.Cu" signal "IN4")
		(26 "In12.Cu" signal "GND5")
		(28 "In13.Cu" signal "IN5")
		(30 "In14.Cu" signal "GND6")
		(32 "In15.Cu" signal "IN6")
		(34 "In16.Cu" signal "GND7")
		(2 "B.Cu" signal "BOTTOM")
		(9 "F.Adhes" user "F.Adhesive")
		(11 "B.Adhes" user "B.Adhesive")
		(13 "F.Paste" user "Package Geometry/Pastemask Top")
		(15 "B.Paste" user "Package Geometry/Pastemask Bottom")
		(5 "F.SilkS" user "Ref Des/Silkscreen Top")
		(7 "B.SilkS" user "Ref Des/Silkscreen Bottom")
		(1 "F.Mask" user "Board Geometry/Soldermask Top")
		(3 "B.Mask" user "Board Geometry/Soldermask Bottom")
		(17 "Dwgs.User" user "User.Drawings")
		(19 "Cmts.User" user "User.Comments")
		(21 "Eco1.User" user "User.Eco1")
		(23 "Eco2.User" user "User.Eco2")
		(25 "Edge.Cuts" user "Board Geometry/Outline")
		(27 "Margin" user)
		(31 "F.CrtYd" user "Package Geometry/Place Bound Top")
		(29 "B.CrtYd" user "Package Geometry/Place Bound Bottom")
		(35 "F.Fab" user "Ref Des/Assembly Top")
		(33 "B.Fab" user "Ref Des/Assembly Bottom")
	)
	(footprint ""
		(layer "F.Cu")
		(at 304.301398 -431.2539)
		(property "Reference" "R4132"
			(at 0 0 0)
			(layer "F.SilkS")
			(hide yes)
			(effects
				(font
					(size 1.27 1.27)
				)
			)
		)
		(property "Value" ""
			(at 0 0 0)
			(layer "F.Fab")
			(effects
				(font
					(size 1.27 1.27)
				)
			)
		)
		(duplicate_pad_numbers_are_jumpers no)
		(fp_line
			(start -0.7874 -0.4064)
			(end 0.7874 -0.4064)
			(stroke
				(width 0.1524)
				(type default)
			)
			(layer "F.SilkS")
		)
		(fp_line
			(start -0.7874 0.4064)
			(end -0.7874 -0.4064)
			(stroke
				(width 0.1524)
				(type default)
			)
			(layer "F.SilkS")
		)
		(fp_line
			(start 0.7874 -0.4064)
			(end 0.7874 0.4064)
			(stroke
				(width 0.1524)
				(type default)
			)
			(layer "F.SilkS")
		)
		(fp_line
			(start 0.7874 0.4064)
			(end -0.7874 0.4064)
			(stroke
				(width 0.1524)
				(type default)
			)
			(layer "F.SilkS")
		)
		(fp_line
			(start -0.67945 -0.305054)
			(end -0.12065 -0.305054)
			(stroke
				(width 0.1)
				(type default)
			)
			(layer "F.Fab")
		)
		(fp_line
			(start -0.67945 0.3048)
			(end -0.67945 -0.305054)
			(stroke
				(width 0.1)
				(type default)
			)
			(layer "F.Fab")
		)
		(fp_line
			(start -0.12065 -0.305054)
			(end -0.12065 -0.2794)
			(stroke
				(width 0.1)
				(type default)
			)
			(layer "F.Fab")
		)
		(fp_line
			(start -0.12065 -0.2794)
			(end 0.12065 -0.2794)
			(stroke
				(width 0.1)
				(type default)
			)
			(layer "F.Fab")
		)
		(fp_line
			(start -0.12065 0.2794)
			(end -0.12065 0.3048)
			(stroke
				(width 0.1)
				(type default)
			)
			(layer "F.Fab")
		)
		(fp_line
			(start -0.12065 0.3048)
			(end -0.67945 0.3048)
			(stroke
				(width 0.1)
				(type default)
			)
			(layer "F.Fab")
		)
		(fp_line
			(start 0.120396 0.2794)
			(end -0.12065 0.2794)
			(stroke
				(width 0.1)
				(type default)
			)
			(layer "F.Fab")
		)
		(fp_line
			(start 0.120396 0.3048)
			(end 0.120396 0.2794)
			(stroke
				(width 0.1)
				(type default)
			)
			(layer "F.Fab")
		)
		(fp_line
			(start 0.12065 -0.3048)
			(end 0.67945 -0.3048)
			(stroke
				(width 0.1)
				(type default)
			)
			(layer "F.Fab")
		)
		(fp_line
			(start 0.12065 -0.2794)
			(end 0.12065 -0.3048)
			(stroke
				(width 0.1)
				(type default)
			)
			(layer "F.Fab")
		)
		(fp_line
			(start 0.67945 -0.3048)
			(end 0.67945 0.3048)
			(stroke
				(width 0.1)
				(type default)
			)
			(layer "F.Fab")
		)
		(fp_line
			(start 0.67945 0.3048)
			(end 0.120396 0.3048)
			(stroke
				(width 0.1)
				(type default)
			)
			(layer "F.Fab")
		)
		(pad "1" smd circle
			(at -0.40005 0)
			(size 0 0)
			(layers "F.Cu" "F.Mask" "F.Paste")
			(net "GPU_3V3IO_RSVD3_FFU")
		)
		(pad "2" smd circle
			(at 0.40005 0)
			(size 0 0)
			(layers "F.Cu" "F.Mask" "F.Paste")
			(net "GND")
		)
	)
	(footprint ""
		(layer "F.Cu")
		(at 38.443662 -424.202098)
		(property "Reference" "R3291"
			(at 0 0 0)
			(layer "F.SilkS")
			(hide yes)
			(effects
				(font
					(size 1.27 1.27)
				)
			)
		)
		(property "Value" ""
			(at 0 0 0)
			(layer "F.Fab")
			(effects
				(font
					(size 1.27 1.27)
				)
			)
		)
		(duplicate_pad_numbers_are_jumpers no)
		(fp_line
			(start -0.7874 -0.4064)
			(end 0.7874 -0.4064)
			(stroke
				(width 0.1524)
				(type default)
			)
			(layer "F.SilkS")
		)
		(fp_line
			(start -0.7874 0.4064)
			(end -0.7874 -0.4064)
			(stroke
				(width 0.1524)
				(type default)
			)
			(layer "F.SilkS")
		)
		(fp_line
			(start 0.7874 -0.4064)
			(end 0.7874 0.4064)
			(stroke
				(width 0.1524)
				(type default)
			)
			(layer "F.SilkS")
		)
		(fp_line
			(start 0.7874 0.4064)
			(end -0.7874 0.4064)
			(stroke
				(width 0.1524)
				(type default)
			)
			(layer "F.SilkS")
		)
		(fp_line
			(start -0.67945 -0.305054)
			(end -0.12065 -0.305054)
			(stroke
				(width 0.1)
				(type default)
			)
			(layer "F.Fab")
		)
		(fp_line
			(start -0.67945 0.3048)
			(end -0.67945 -0.305054)
			(stroke
				(width 0.1)
				(type default)
			)
			(layer "F.Fab")
		)
		(fp_line
			(start -0.12065 -0.305054)
			(end -0.12065 -0.2794)
			(stroke
				(width 0.1)
				(type default)
			)
			(layer "F.Fab")
		)
		(fp_line
			(start -0.12065 -0.2794)
			(end 0.12065 -0.2794)
			(stroke
				(width 0.1)
				(type default)
			)
			(layer "F.Fab")
		)
		(fp_line
			(start -0.12065 0.2794)
			(end -0.12065 0.3048)
			(stroke
				(width 0.1)
				(type default)
			)
			(layer "F.Fab")
		)
		(fp_line
			(start -0.12065 0.3048)
			(end -0.67945 0.3048)
			(stroke
				(width 0.1)
				(type default)
			)
			(layer "F.Fab")
		)
		(fp_line
			(start 0.120396 0.2794)
			(end -0.12065 0.2794)
			(stroke
				(width 0.1)
				(type default)
			)
			(layer "F.Fab")
		)
		(fp_line
			(start 0.120396 0.3048)
			(end 0.120396 0.2794)
			(stroke
				(width 0.1)
				(type default)
			)
			(layer "F.Fab")
		)
		(fp_line
			(start 0.12065 -0.3048)
			(end 0.67945 -0.3048)
			(stroke
				(width 0.1)
				(type default)
			)
			(layer "F.Fab")
		)
		(fp_line
			(start 0.12065 -0.2794)
			(end 0.12065 -0.3048)
			(stroke
				(width 0.1)
				(type default)
			)
			(layer "F.Fab")
		)
		(fp_line
			(start 0.67945 -0.3048)
			(end 0.67945 0.3048)
			(stroke
				(width 0.1)
				(type default)
			)
			(layer "F.Fab")
		)
		(fp_line
			(start 0.67945 0.3048)
			(end 0.120396 0.3048)
			(stroke
				(width 0.1)
				(type default)
			)
			(layer "F.Fab")
		)
		(pad "1" smd circle
			(at -0.40005 0)
			(size 0 0)
			(layers "F.Cu" "F.Mask" "F.Paste")
			(net "PU_TEST")
		)
		(pad "2" smd circle
			(at 0.40005 0)
			(size 0 0)
			(layers "F.Cu" "F.Mask" "F.Paste")
			(net "GND")
		)
	)
)
